(kicad_pcb
	(version 20260206)
	(generator "pcbnew")
	(generator_version "10.0")
	(general
		(thickness 1.6)
		(legacy_teardrops no)
	)
	(paper "A4")
	(title_block
		(title "v1-chassis-manager — T6M_CM_d_v01_1031_1645.brd")
		(comment 1 "Open CloudServer (Microsoft) / footprints 877-877 of 2512")
	)
	(layers
		(0 "F.Cu" signal "TOP")
		(4 "In1.Cu" signal "GND1")
		(6 "In2.Cu" signal "IN1")
		(8 "In3.Cu" signal "VCC1")
		(10 "In4.Cu" signal "VCC2")
		(12 "In5.Cu" signal "GND2")
		(14 "In6.Cu" signal "IN2")
		(16 "In7.Cu" signal "IN3")
		(18 "In8.Cu" signal "GND3")
		(2 "B.Cu" signal "BOTTOM")
		(9 "F.Adhes" user "F.Adhesive")
		(11 "B.Adhes" user "B.Adhesive")
		(13 "F.Paste" user "Package Geometry/Pastemask Top")
		(15 "B.Paste" user "Package Geometry/Pastemask Bottom")
		(5 "F.SilkS" user "Ref Des/Silkscreen Top")
		(7 "B.SilkS" user "Ref Des/Silkscreen Bottom")
		(1 "F.Mask" user "Board Geometry/Soldermask Top")
		(3 "B.Mask" user "Board Geometry/Soldermask Bottom")
		(17 "Dwgs.User" user "User.Drawings")
		(19 "Cmts.User" user "User.Comments")
		(21 "Eco1.User" user "User.Eco1")
		(23 "Eco2.User" user "User.Eco2")
		(25 "Edge.Cuts" user "Board Geometry/Outline")
		(27 "Margin" user)
		(31 "F.CrtYd" user "Package Geometry/Place Bound Top")
		(29 "B.CrtYd" user "Package Geometry/Place Bound Bottom")
		(35 "F.Fab" user "Ref Des/Assembly Top")
		(33 "B.Fab" user "Ref Des/Assembly Bottom")
	)
	(footprint ""
		(layer "F.Cu")
		(at 44.567602 -154.922982 90)
		(property "Reference" "U35"
			(at -0.534416 -6.27888 90)
			(unlocked yes)
			(layer "F.SilkS")
			(effects
				(font
					(size 0.7874 0.5842)
					(thickness 0.1524)
				)
				(justify left)
			)
		)
		(property "Value" ""
			(at 0 0 90)
			(layer "F.Fab")
			(effects
				(font
					(size 1.27 1.27)
				)
			)
		)
		(duplicate_pad_numbers_are_jumpers no)
		(fp_line
			(start 0.750062 -5.207)
			(end 0.750062 -5.715)
			(stroke
				(width 0.1524)
				(type default)
			)
			(layer "F.SilkS")
		)
		(fp_line
			(start 4.500118 -4.500118)
			(end 4.500118 -4.0132)
			(stroke
				(width 0.1524)
				(type default)
			)
			(layer "F.SilkS")
		)
		(fp_line
			(start 4.0386 -4.500118)
			(end 4.500118 -4.500118)
			(stroke
				(width 0.1524)
				(type default)
			)
			(layer "F.SilkS")
		)
		(fp_line
			(start -4.487418 -4.004818)
			(end -4.004818 -4.487418)
			(stroke
				(width 0.1524)
				(type default)
			)
			(layer "F.SilkS")
		)
		(fp_line
			(start 5.207 -1.75006)
			(end 5.715 -1.75006)
			(stroke
				(width 0.1524)
				(type default)
			)
			(layer "F.SilkS")
		)
		(fp_line
			(start -5.207 -1.75006)
			(end -5.715 -1.75006)
			(stroke
				(width 0.1524)
				(type default)
			)
			(layer "F.SilkS")
		)
		(fp_line
			(start 5.207 0.249936)
			(end 6.223 0.249936)
			(stroke
				(width 0.1524)
				(type default)
			)
			(layer "F.SilkS")
		)
		(fp_line
			(start -5.207 0.750062)
			(end -6.223 0.750062)
			(stroke
				(width 0.1524)
				(type default)
			)
			(layer "F.SilkS")
		)
		(fp_line
			(start 5.207 2.750058)
			(end 5.715 2.750058)
			(stroke
				(width 0.1524)
				(type default)
			)
			(layer "F.SilkS")
		)
		(fp_line
			(start -5.207 3.24993)
			(end -5.715 3.24993)
			(stroke
				(width 0.1524)
				(type default)
			)
			(layer "F.SilkS")
		)
		(fp_line
			(start 4.500118 4.0386)
			(end 4.500118 4.500118)
			(stroke
				(width 0.1524)
				(type default)
			)
			(layer "F.SilkS")
		)
		(fp_line
			(start -4.500118 4.474718)
			(end -4.500118 4.0132)
			(stroke
				(width 0.1524)
				(type default)
			)
			(layer "F.SilkS")
		)
		(fp_line
			(start 4.500118 4.500118)
			(end 4.0132 4.500118)
			(stroke
				(width 0.1524)
				(type default)
			)
			(layer "F.SilkS")
		)
		(fp_line
			(start -4.0132 4.500118)
			(end -4.474718 4.500118)
			(stroke
				(width 0.1524)
				(type default)
			)
			(layer "F.SilkS")
		)
		(fp_line
			(start -4.474718 4.500118)
			(end -4.500118 4.474718)
			(stroke
				(width 0.1524)
				(type default)
			)
			(layer "F.SilkS")
		)
		(fp_line
			(start 2.750058 5.207)
			(end 2.750058 6.223)
			(stroke
				(width 0.1524)
				(type default)
			)
			(layer "F.SilkS")
		)
		(fp_line
			(start 0.249936 5.207)
			(end 0.249936 5.715)
			(stroke
				(width 0.1524)
				(type default)
			)
			(layer "F.SilkS")
		)
		(fp_line
			(start -2.249932 5.207)
			(end -2.249932 6.223)
			(stroke
				(width 0.1524)
				(type default)
			)
			(layer "F.SilkS")
		)
		(fp_poly
			(pts
				(xy -5.1562 -3.761486) (xy -6.6802 -4.321556) (xy -6.6802 -3.178556)
			)
			(stroke
				(width 0)
				(type default)
			)
			(fill yes)
			(layer "F.SilkS")
		)
		(fp_poly
			(pts
				(xy -4.500118 4.500118) (xy -3.8862 4.500118) (xy -3.8862 5.0292) (xy -3.8608 5.0292) (xy 3.8608 5.0292)
				(xy 3.8862 5.0292) (xy 3.8862 4.500118) (xy 4.500118 4.500118) (xy 4.500118 3.8862) (xy 5.0292 3.8862)
				(xy 5.0292 3.8608) (xy 5.0292 -3.8608) (xy 5.0292 -3.8862) (xy 4.500118 -3.8862) (xy 4.500118 -4.500118)
				(xy 3.8862 -4.500118) (xy 3.8862 -5.0292) (xy 3.8608 -5.0292) (xy -3.8608 -5.0292) (xy -3.8862 -5.0292)
				(xy -3.8862 -4.500118) (xy -4.500118 -4.500118) (xy -4.500118 -3.8862) (xy -5.0292 -3.8862) (xy -5.0292 -3.8608)
				(xy -5.0292 3.8608) (xy -5.0292 3.8862) (xy -4.500118 3.8862)
			)
			(stroke
				(width 0)
				(type default)
			)
			(fill no)
			(layer "F.CrtYd")
		)
		(fp_line
			(start 4.500118 -4.500118)
			(end 4.500118 4.500118)
			(stroke
				(width 0.1)
				(type default)
			)
			(layer "F.Fab")
		)
		(fp_line
			(start -4.500118 -4.500118)
			(end 4.500118 -4.500118)
			(stroke
				(width 0.1)
				(type default)
			)
			(layer "F.Fab")
		)
		(fp_line
			(start 4.500118 4.500118)
			(end -4.500118 4.500118)
			(stroke
				(width 0.1)
				(type default)
			)
			(layer "F.Fab")
		)
		(fp_line
			(start -4.500118 4.500118)
			(end -4.500118 -4.500118)
			(stroke
				(width 0.1)
				(type default)
			)
			(layer "F.Fab")
		)
		(fp_text user "49"
			(at 3.602228 -5.41782 90)
			(unlocked yes)
			(layer "F.SilkS")
			(effects
				(font
					(size 0.635 0.4064)
					(thickness 0.1524)
				)
				(justify left)
			)
		)
		(fp_text user "48"
			(at 4.753864 -4.321556 90)
			(unlocked yes)
			(layer "F.SilkS")
			(effects
				(font
					(size 0.635 0.4064)
					(thickness 0.1524)
				)
				(justify left)
			)
		)
		(fp_text user "33"
			(at 5.189728 3.653028 90)
			(unlocked yes)
			(layer "F.SilkS")
			(effects
				(font
					(size 0.635 0.4064)
					(thickness 0.1524)
				)
				(justify left)
			)
		)
		(fp_text user "16"
			(at -6.089904 4.025392 90)
			(unlocked yes)
			(layer "F.SilkS")
			(effects
				(font
					(size 0.635 0.4064)
					(thickness 0.1524)
				)
				(justify left)
			)
		)
		(fp_text user "32"
			(at 4.118356 5.121402 90)
			(unlocked yes)
			(layer "F.SilkS")
			(effects
				(font
					(size 0.635 0.4064)
					(thickness 0.1524)
				)
				(justify left)
			)
		)
		(fp_text user "17"
			(at -4.20116 5.569204 90)
			(unlocked yes)
			(layer "F.SilkS")
			(effects
				(font
					(size 0.635 0.4064)
					(thickness 0.1524)
				)
				(justify left)
			)
		)
		(pad "1" smd rect
			(at -4.549902 -3.750056)
			(size 0.254 0.9144)
			(layers "F.Cu" "F.Mask" "F.Paste")
			(net "P3V3_NODE1")
		)
		(pad "2" smd rect
			(at -4.549902 -3.24993)
			(size 0.254 0.9144)
			(layers "F.Cu" "F.Mask" "F.Paste")
			(net "LAN1_NC_SI_CLK_IN")
		)
		(pad "3" smd rect
			(at -4.549902 -2.750058)
			(size 0.254 0.9144)
			(layers "F.Cu" "F.Mask" "F.Paste")
			(net "LAN1_NC_SI_CRS_DV")
		)
		(pad "4" smd rect
			(at -4.549902 -2.249932)
			(size 0.254 0.9144)
			(layers "F.Cu" "F.Mask" "F.Paste")
			(net "P1V05_LAN1")
		)
		(pad "5" smd rect
			(at -4.549902 -1.75006)
			(size 0.254 0.9144)
			(layers "F.Cu" "F.Mask" "F.Paste")
			(net "LAN1_NC_SI_RXD1")
		)
		(pad "6" smd rect
			(at -4.549902 -1.249934)
			(size 0.254 0.9144)
			(layers "F.Cu" "F.Mask" "F.Paste")
			(net "LAN1_NC_SI_RXD0")
		)
		(pad "7" smd rect
			(at -4.549902 -0.750062)
			(size 0.254 0.9144)
			(layers "F.Cu" "F.Mask" "F.Paste")
			(net "LAN1_NC_SI_TX_EN")
		)
		(pad "8" smd rect
			(at -4.549902 -0.249936)
			(size 0.254 0.9144)
			(layers "F.Cu" "F.Mask" "F.Paste")
			(net "LAN1_NC_SI_TDX1")
		)
		(pad "9" smd rect
			(at -4.549902 0.249936)
			(size 0.254 0.9144)
			(layers "F.Cu" "F.Mask" "F.Paste")
			(net "LAN1_NC_SI_TDX0")
		)
		(pad "10" smd rect
			(at -4.549902 0.750062)
			(size 0.254 0.9144)
			(layers "F.Cu" "F.Mask" "F.Paste")
			(net "P3V3_NODE1")
		)
		(pad "11" smd rect
			(at -4.549902 1.249934)
			(size 0.254 0.9144)
			(layers "F.Cu" "F.Mask" "F.Paste")
			(net "P1V05_LAN1")
		)
		(pad "12" smd rect
			(at -4.549902 1.75006)
			(size 0.254 0.9144)
			(layers "F.Cu" "F.Mask" "F.Paste")
			(net "SPI_LAN1_NVM_SI")
		)
		(pad "13" smd rect
			(at -4.549902 2.249932)
			(size 0.254 0.9144)
			(layers "F.Cu" "F.Mask" "F.Paste")
			(net "SPI_LAN1_NVM_SK")
		)
		(pad "14" smd rect
			(at -4.549902 2.750058)
			(size 0.254 0.9144)
			(layers "F.Cu" "F.Mask" "F.Paste")
			(net "SPI_LAN1_NVM_SO")
		)
		(pad "15" smd rect
			(at -4.549902 3.24993)
			(size 0.254 0.9144)
			(layers "F.Cu" "F.Mask" "F.Paste")
			(net "SPI_LAN1_NVM_CS_N")
		)
		(pad "16" smd rect
			(at -4.549902 3.750056)
			(size 0.254 0.9144)
			(layers "F.Cu" "F.Mask" "F.Paste")
			(net "IRQ_LVC3_CPU_NODE1_WAKE_L")
		)
		(pad "17" smd rect
			(at -3.750056 4.549902 90)
			(size 0.254 0.9144)
			(layers "F.Cu" "F.Mask" "F.Paste")
			(net "PLT_RST_LAN1_N")
		)
		(pad "18" smd rect
			(at -3.24993 4.549902 90)
			(size 0.254 0.9144)
			(layers "F.Cu" "F.Mask" "F.Paste")
			(net "P1V05_LAN1")
		)
		(pad "19" smd rect
			(at -2.750058 4.549902 90)
			(size 0.254 0.9144)
			(layers "F.Cu" "F.Mask" "F.Paste")
			(net "P1V9_LAN1")
		)
		(pad "20" smd rect
			(at -2.249932 4.549902 90)
			(size 0.254 0.9144)
			(layers "F.Cu" "F.Mask" "F.Paste")
			(net "PCIE_LAN1_RX_C_DN")
		)
		(pad "21" smd rect
			(at -1.75006 4.549902 90)
			(size 0.254 0.9144)
			(layers "F.Cu" "F.Mask" "F.Paste")
			(net "PCIE_LAN1_RX_C_DP")
		)
		(pad "22" smd rect
			(at -1.249934 4.549902 90)
			(size 0.254 0.9144)
			(layers "F.Cu" "F.Mask" "F.Paste")
			(net "P1V9_LAN1")
		)
		(pad "23" smd rect
			(at -0.750062 4.549902 90)
			(size 0.254 0.9144)
			(layers "F.Cu" "F.Mask" "F.Paste")
			(net "P2E_CPU_NIC1_NODE1_TX_DN")
		)
		(pad "24" smd rect
			(at -0.249936 4.549902 90)
			(size 0.254 0.9144)
			(layers "F.Cu" "F.Mask" "F.Paste")
			(net "P2E_CPU_NIC1_NODE1_TX_DP")
		)
		(pad "25" smd rect
			(at 0.249936 4.549902 90)
			(size 0.254 0.9144)
			(layers "F.Cu" "F.Mask" "F.Paste")
			(net "CLK_100M_NIC1_NODE1_DN")
		)
		(pad "26" smd rect
			(at 0.750062 4.549902 90)
			(size 0.254 0.9144)
			(layers "F.Cu" "F.Mask" "F.Paste")
			(net "CLK_100M_NIC1_NODE1_DP")
		)
		(pad "27" smd rect
			(at 1.249934 4.549902 90)
			(size 0.254 0.9144)
			(layers "F.Cu" "F.Mask" "F.Paste")
			(net "P1V05_LAN1")
		)
		(pad "28" smd rect
			(at 1.75006 4.549902 90)
			(size 0.254 0.9144)
			(layers "F.Cu" "F.Mask" "F.Paste")
			(net "LAN1_DISABLE_N")
		)
		(pad "29" smd rect
			(at 2.249932 4.549902 90)
			(size 0.254 0.9144)
			(layers "F.Cu" "F.Mask" "F.Paste")
			(net "LAN1_TEST_EN")
		)
		(pad "30" smd rect
			(at 2.750058 4.549902 90)
			(size 0.254 0.9144)
			(layers "F.Cu" "F.Mask" "F.Paste")
			(net "LAN1_LED_ACT_N")
		)
		(pad "31" smd rect
			(at 3.24993 4.549902 90)
			(size 0.254 0.9144)
			(layers "F.Cu" "F.Mask" "F.Paste")
			(net "LAN1_LED_LINK_100_N")
		)
		(pad "32" smd rect
			(at 3.750056 4.549902 90)
			(size 0.254 0.9144)
			(layers "F.Cu" "F.Mask" "F.Paste")
			(net "P3V3_NODE1")
		)
		(pad "33" smd rect
			(at 4.549902 3.750056 180)
			(size 0.254 0.9144)
			(layers "F.Cu" "F.Mask" "F.Paste")
			(net "LAN1_LED_LINK_1000_N")
		)
		(pad "34" smd rect
			(at 4.549902 3.24993 180)
			(size 0.254 0.9144)
			(layers "F.Cu" "F.Mask" "F.Paste")
			(net "SMB_LAN1_CLK")
		)
		(pad "35" smd rect
			(at 4.549902 2.750058 180)
			(size 0.254 0.9144)
			(layers "F.Cu" "F.Mask" "F.Paste")
			(net "SMB_LAN1_ALT_N")
		)
		(pad "36" smd rect
			(at 4.549902 2.249932 180)
			(size 0.254 0.9144)
			(layers "F.Cu" "F.Mask" "F.Paste")
			(net "SMB_LAN1_DAT")
		)
		(pad "37" smd rect
			(at 4.549902 1.75006 180)
			(size 0.254 0.9144)
			(layers "F.Cu" "F.Mask" "F.Paste")
			(net "P1V05_LAN1")
		)
		(pad "38" smd rect
			(at 4.549902 1.249934 180)
			(size 0.254 0.9144)
			(layers "F.Cu" "F.Mask" "F.Paste")
			(net "PU_LAN1_TMS")
		)
		(pad "39" smd rect
			(at 4.549902 0.750062 180)
			(size 0.254 0.9144)
			(layers "F.Cu" "F.Mask" "F.Paste")
			(net "LAN1_AUX_PWR")
		)
		(pad "40" smd rect
			(at 4.549902 0.249936 180)
			(size 0.254 0.9144)
			(layers "F.Cu" "F.Mask" "F.Paste")
			(net "PU_LAN1_TDI")
		)
		(pad "41" smd rect
			(at 4.549902 -0.249936 180)
			(size 0.254 0.9144)
			(layers "F.Cu" "F.Mask" "F.Paste")
			(net "P1V05_LAN1")
		)
		(pad "42" smd rect
			(at 4.549902 -0.750062 180)
			(size 0.254 0.9144)
			(layers "F.Cu" "F.Mask" "F.Paste")
			(net "LAN1_XTAL_OUT")
		)
		(pad "43" smd rect
			(at 4.549902 -1.249934 180)
			(size 0.254 0.9144)
			(layers "F.Cu" "F.Mask" "F.Paste")
			(net "LAN1_XTAL_IN")
		)
		(pad "44" smd rect
			(at 4.549902 -1.75006 180)
			(size 0.254 0.9144)
			(layers "F.Cu" "F.Mask" "F.Paste")
			(net "P1V9_LAN1")
		)
		(pad "45" smd rect
			(at 4.549902 -2.249932 180)
			(size 0.254 0.9144)
			(layers "F.Cu" "F.Mask" "F.Paste")
			(net "N21311590")
		)
		(pad "46" smd rect
			(at 4.549902 -2.750058 180)
			(size 0.254 0.9144)
			(layers "F.Cu" "F.Mask" "F.Paste")
			(net "N21311592")
		)
		(pad "47" smd rect
			(at 4.549902 -3.24993 180)
			(size 0.254 0.9144)
			(layers "F.Cu" "F.Mask" "F.Paste")
			(net "P1V9_LAN1")
		)
		(pad "48" smd rect
			(at 4.549902 -3.750056 180)
			(size 0.254 0.9144)
			(layers "F.Cu" "F.Mask" "F.Paste")
			(net "LAN1_RST")
		)
		(pad "49" smd rect
			(at 3.750056 -4.549902 90)
			(size 0.254 0.9144)
			(layers "F.Cu" "F.Mask" "F.Paste")
			(net "LAN1_MDI3_DN")
		)
		(pad "50" smd rect
			(at 3.24993 -4.549902 90)
			(size 0.254 0.9144)
			(layers "F.Cu" "F.Mask" "F.Paste")
			(net "LAN1_MDI3_DP")
		)
		(pad "51" smd rect
			(at 2.750058 -4.549902 90)
			(size 0.254 0.9144)
			(layers "F.Cu" "F.Mask" "F.Paste")
			(net "P1V9_LAN1")
		)
		(pad "52" smd rect
			(at 2.249932 -4.549902 90)
			(size 0.254 0.9144)
			(layers "F.Cu" "F.Mask" "F.Paste")
			(net "LAN1_MDI2_DN")
		)
		(pad "53" smd rect
			(at 1.75006 -4.549902 90)
			(size 0.254 0.9144)
			(layers "F.Cu" "F.Mask" "F.Paste")
			(net "LAN1_MDI2_DP")
		)
		(pad "54" smd rect
			(at 1.249934 -4.549902 90)
			(size 0.254 0.9144)
			(layers "F.Cu" "F.Mask" "F.Paste")
			(net "LAN1_MDI1_DN")
		)
		(pad "55" smd rect
			(at 0.750062 -4.549902 90)
			(size 0.254 0.9144)
			(layers "F.Cu" "F.Mask" "F.Paste")
			(net "LAN1_MDI1_DP")
		)
		(pad "56" smd rect
			(at 0.249936 -4.549902 90)
			(size 0.254 0.9144)
			(layers "F.Cu" "F.Mask" "F.Paste")
			(net "P1V9_LAN1")
		)
		(pad "57" smd rect
			(at -0.249936 -4.549902 90)
			(size 0.254 0.9144)
			(layers "F.Cu" "F.Mask" "F.Paste")
			(net "LAN1_MDI0_DN")
		)
		(pad "58" smd rect
			(at -0.750062 -4.549902 90)
			(size 0.254 0.9144)
			(layers "F.Cu" "F.Mask" "F.Paste")
			(net "LAN1_MDI0_DP")
		)
		(pad "59" smd rect
			(at -1.249934 -4.549902 90)
			(size 0.254 0.9144)
			(layers "F.Cu" "F.Mask" "F.Paste")
			(net "LAN1_DIS_REG10")
		)
		(pad "60" smd rect
			(at -1.75006 -4.549902 90)
			(size 0.254 0.9144)
			(layers "F.Cu" "F.Mask" "F.Paste")
			(net "P1V05_LAN1")
		)
		(pad "61" smd rect
			(at -2.249932 -4.549902 90)
			(size 0.254 0.9144)
			(layers "F.Cu" "F.Mask" "F.Paste")
			(net "P1V9_LAN1")
		)
		(pad "62" smd rect
			(at -2.750058 -4.549902 90)
			(size 0.254 0.9144)
			(layers "F.Cu" "F.Mask" "F.Paste")
			(net "Net_1819")
		)
		(pad "63" smd rect
			(at -3.24993 -4.549902 90)
			(size 0.254 0.9144)
			(layers "F.Cu" "F.Mask" "F.Paste")
			(net "P1V9_LAN1")
		)
		(pad "64" smd rect
			(at -3.750056 -4.549902 90)
			(size 0.254 0.9144)
			(layers "F.Cu" "F.Mask" "F.Paste")
			(net "LAN1_CTRL_P1V9")
		)
		(pad "TH" smd rect
			(at 0 0 90)
			(size 5.4102 5.4102)
			(layers "F.Cu" "F.Mask" "F.Paste")
			(net "GND")
		)
		(zone
			(layer "F.Cu")
			(hatch none 0.5)
			(connect_pads
				(clearance 0)
			)
			(min_thickness 0.25)
			(keepout
				(tracks not_allowed)
				(vias allowed)
				(pads allowed)
				(copperpour not_allowed)
				(footprints allowed)
			)
			(placement
				(enabled no)
				(sheetname "")
			)
			(fill
				(thermal_gap 0.5)
				(thermal_bridge_width 0.5)
				(island_removal_mode 0)
			)
			(polygon
				(pts
					(xy 40.554402 -150.909782) (xy 40.554402 -158.936182) (xy 48.580802 -158.936182) (xy 48.580802 -150.909782)
					(xy 41.799002 -150.909782) (xy 41.799002 -152.128982) (xy 47.361602 -152.128982) (xy 47.361602 -157.716982)
					(xy 41.773602 -157.716982) (xy 41.773602 -150.909782) (xy 41.367202 -150.909782)
				)
			)
		)
		(zone
			(layers "F.Cu" "B.Cu" "In1.Cu" "In2.Cu" "In3.Cu" "In4.Cu" "In5.Cu" "In6.Cu"
				"In7.Cu" "In8.Cu"
			)
			(hatch none 0.5)
			(connect_pads
				(clearance 0)
			)
			(min_thickness 0.25)
			(keepout
				(tracks allowed)
				(vias not_allowed)
				(pads allowed)
				(copperpour not_allowed)
				(footprints allowed)
			)
			(placement
				(enabled no)
				(sheetname "")
			)
			(fill
				(thermal_gap 0.5)
				(thermal_bridge_width 0.5)
				(island_removal_mode 0)
			)
			(polygon
				(pts
					(xy 40.554402 -150.909782) (xy 40.554402 -158.936182) (xy 48.580802 -158.936182) (xy 48.580802 -150.909782)
					(xy 41.799002 -150.909782) (xy 41.799002 -152.128982) (xy 47.361602 -152.128982) (xy 47.361602 -157.716982)
					(xy 41.773602 -157.716982) (xy 41.773602 -150.909782)
				)
			)
		)
	)
)
